(kicad_pcb
	(version 20211014)
	(generator pcbnew)
	(general
    (thickness 1.6)
  )
	(paper "A4")
	(title_block
    (title "SA800U (Snapdragon 845) Baseboard")
    (date "2023-10-19")
    (rev "1.0.3")
    (company "Antmicro Ltd.")
    (comment 1 "www.antmicro.com")
		(comment 9 "footprints 322-331 of 589")
	)
	(layers
    (0 "F.Cu" signal)
    (1 "In1.Cu" power)
    (2 "In2.Cu" signal)
    (3 "In3.Cu" signal)
    (4 "In4.Cu" power)
    (31 "B.Cu" signal)
    (32 "B.Adhes" user "B.Adhesive")
    (33 "F.Adhes" user "F.Adhesive")
    (34 "B.Paste" user)
    (35 "F.Paste" user)
    (36 "B.SilkS" user "B.Silkscreen")
    (37 "F.SilkS" user "F.Silkscreen")
    (38 "B.Mask" user)
    (39 "F.Mask" user)
    (40 "Dwgs.User" user "User.Drawings")
    (41 "Cmts.User" user "User.Comments")
    (42 "Eco1.User" user "User.Eco1")
    (43 "Eco2.User" user "User.Eco2")
    (44 "Edge.Cuts" user)
    (45 "Margin" user)
    (46 "B.CrtYd" user "B.Courtyard")
    (47 "F.CrtYd" user "F.Courtyard")
    (48 "B.Fab" user)
    (49 "F.Fab" user)
  )
	(footprint "sa800u-baseboard-hw-footprints:C_0603_1608Metric" (layer "B.Cu")
    (tedit 5D5E94D2)
    (at 84.9 141.2 90)
    (descr "Capacitor SMD 0603")
    (tags "capacitor 0603")
    (property "Author" "Antmicro")
    (property "Dielectric" "")
    (property "License" "Apache-2.0")
    (property "MPN" "C1608X5R1V475M080AC")
    (property "Manufacturer" "TDK")
    (property "Sheetfile" "usb-pd.kicad_sch")
    (property "Sheetname" "USB-PD")
    (property "Val" "4u7")
    (property "Voltage" "")
    (attr smd)
    (fp_text reference "C152" (at 1.45 1.38 270) (layer "B.SilkS")
      (effects (font (size 0.7 0.7) (thickness 0.15)) (justify left bottom mirror))
    )
    (fp_text value "C_4u7_0603" (at 0 -1.6 270) (layer "B.Fab")
      (effects (font (size 0.7 0.7) (thickness 0.15)) (justify left bottom mirror))
    )
    (fp_text user "License: Apache-2.0" (at -1.682 -5.895 270) (layer "B.Fab") hide
      (effects (font (size 0.7 0.7) (thickness 0.15)) (justify left bottom mirror))
    )
    (fp_text user "Author: Antmicro" (at -1.682 -4.894 270) (layer "B.Fab") hide
      (effects (font (size 0.7 0.7) (thickness 0.15)) (justify left bottom mirror))
    )
    (fp_text user "${REFERENCE}" (at -1.682 -3.895 270) (layer "B.Fab") hide
      (effects (font (size 0.7 0.7) (thickness 0.15)) (justify left bottom mirror))
    )
    (fp_line (start -0.3 0.3) (end 0.3 0.3) (layer "B.SilkS") (width 0.15))
    (fp_line (start -0.3 -0.3) (end 0.3 -0.3) (layer "B.SilkS") (width 0.15))
    (fp_rect (start -1.24 0.7) (end 1.24 -0.7) (layer "B.CrtYd") (width 0.05) (fill none))
    (fp_rect (start -0.8 0.4) (end 0.8 -0.4) (layer "B.Fab") (width 0.15) (fill none))
    (pad "1" smd roundrect (at -0.7 0 90) (size 0.6 0.8) (layers "B.Cu" "B.Paste" "B.Mask") (roundrect_rratio 0.2)
      (net 107 "/USB-PD/PD_VBUS") (pintype "passive"))
    (pad "2" smd roundrect (at 0.7 0 90) (size 0.6 0.8) (layers "B.Cu" "B.Paste" "B.Mask") (roundrect_rratio 0.2)
      (net 1 "GND") (pintype "passive"))
  )
	(footprint "sa800u-baseboard-hw-footprints:R_0402_1005Metric" (layer "B.Cu")
    (tedit 5FD9C158)
    (at 62.6 104.7 -90)
    (descr "Resistor SMD 0402")
    (tags "resistor SMD 0402")
    (property "Author" "Antmicro")
    (property "Current" "1A")
    (property "License" "Apache-2.0")
    (property "MPN" "ERJ2GE0R00X")
    (property "Manufacturer" "Panasonic")
    (property "Sheetfile" "poe.kicad_sch")
    (property "Sheetname" "PoE")
    (property "Tolerance" "")
    (property "Val" "0R")
    (attr smd)
    (fp_text reference "R145" (at -1.53 -1.34 90) (layer "B.SilkS")
      (effects (font (size 0.7 0.7) (thickness 0.15)) (justify left bottom mirror))
    )
    (fp_text value "R_0R_0402" (at 0 -1.4 90) (layer "B.Fab")
      (effects (font (size 0.7 0.7) (thickness 0.15)) (justify left bottom mirror))
    )
    (fp_text user "License: Apache-2.0" (at -0.95 -5.169 90) (layer "B.Fab") hide
      (effects (font (size 0.7 0.7) (thickness 0.15)) (justify left bottom mirror))
    )
    (fp_text user "${REFERENCE}" (at -0.95 -3.168 90) (layer "B.Fab") hide
      (effects (font (size 0.7 0.7) (thickness 0.15)) (justify left bottom mirror))
    )
    (fp_text user "Author: Antmicro" (at -0.95 -4.169 90) (layer "B.Fab") hide
      (effects (font (size 0.7 0.7) (thickness 0.15)) (justify left bottom mirror))
    )
    (fp_rect (start -0.93 0.47) (end 0.93 -0.47) (layer "B.CrtYd") (width 0.05) (fill none))
    (fp_rect (start -0.5 0.25) (end 0.5 -0.25) (layer "B.Fab") (width 0.15) (fill none))
    (pad "1" smd roundrect (at -0.485 0 270) (size 0.59 0.64) (layers "B.Cu" "B.Paste" "B.Mask") (roundrect_rratio 0.25)
      (net 7 "GNDD") (pintype "passive"))
    (pad "2" smd roundrect (at 0.485 0 270) (size 0.59 0.64) (layers "B.Cu" "B.Paste" "B.Mask") (roundrect_rratio 0.25)
      (net 174 "/PoE/APD") (pintype "passive"))
  )
	(footprint "sa800u-baseboard-hw-footprints:C_0402_1005Metric" (layer "B.Cu")
    (tedit 616D63CF)
    (at 140.345 106.6 180)
    (descr "Capacitor SMD 0402")
    (tags "capacitor SMD 0402")
    (property "Author" "Antmicro")
    (property "Dielectric" "")
    (property "License" "Apache-2.0")
    (property "MPN" "C1005X6S1A105K050BC")
    (property "Manufacturer" "TDK")
    (property "Sheetfile" "m2.kicad_sch")
    (property "Sheetname" "M2")
    (property "Val" "1u")
    (property "Voltage" "")
    (attr smd)
    (fp_text reference "C113" (at 0.765 -0.29) (layer "B.SilkS")
      (effects (font (size 0.7 0.7) (thickness 0.15)) (justify left bottom mirror))
    )
    (fp_text value "C_1u_0402" (at 0 -1.4) (layer "B.Fab")
      (effects (font (size 0.7 0.7) (thickness 0.15)) (justify left bottom mirror))
    )
    (fp_text user "Author: Antmicro" (at -0.932 -4.17) (layer "B.Fab") hide
      (effects (font (size 0.7 0.7) (thickness 0.15)) (justify left bottom mirror))
    )
    (fp_text user "${REFERENCE}" (at -0.932 -3.168) (layer "B.Fab") hide
      (effects (font (size 0.7 0.7) (thickness 0.15)) (justify left bottom mirror))
    )
    (fp_text user "License: Apache-2.0" (at -0.932 -5.17) (layer "B.Fab") hide
      (effects (font (size 0.7 0.7) (thickness 0.15)) (justify left bottom mirror))
    )
    (fp_rect (start -0.94 0.47) (end 0.94 -0.47) (layer "B.CrtYd") (width 0.05) (fill none))
    (fp_rect (start -0.499 0.249) (end 0.499 -0.249) (layer "B.Fab") (width 0.15) (fill none))
    (pad "1" smd roundrect (at -0.484 0 180) (size 0.59 0.64) (layers "B.Cu" "B.Paste" "B.Mask") (roundrect_rratio 0.25)
      (net 131 "3V3_SYS") (pintype "passive"))
    (pad "2" smd roundrect (at 0.484 0 180) (size 0.59 0.64) (layers "B.Cu" "B.Paste" "B.Mask") (roundrect_rratio 0.25)
      (net 1 "GND") (pintype "passive"))
  )
	(footprint "sa800u-baseboard-hw-footprints:R_0402_1005Metric" (layer "B.Cu")
    (tedit 5FD9C158)
    (at 140.215 98.85)
    (descr "Resistor SMD 0402")
    (tags "resistor SMD 0402")
    (property "Author" "Antmicro")
    (property "License" "Apache-2.0")
    (property "MPN" "CR0402-FX-1002GLF")
    (property "Manufacturer" "Bourns")
    (property "Sheetfile" "m2.kicad_sch")
    (property "Sheetname" "M2")
    (property "Tolerance" "1%")
    (property "Val" "10k")
    (attr smd)
    (fp_text reference "R93" (at 1.025 -0.62 180) (layer "B.SilkS")
      (effects (font (size 0.7 0.7) (thickness 0.15)) (justify left bottom mirror))
    )
    (fp_text value "R_10k_0402" (at 0 -1.4 180) (layer "B.Fab")
      (effects (font (size 0.7 0.7) (thickness 0.15)) (justify left bottom mirror))
    )
    (fp_text user "Author: Antmicro" (at -0.95 -4.169 180) (layer "B.Fab") hide
      (effects (font (size 0.7 0.7) (thickness 0.15)) (justify left bottom mirror))
    )
    (fp_text user "${REFERENCE}" (at -0.95 -3.168 180) (layer "B.Fab") hide
      (effects (font (size 0.7 0.7) (thickness 0.15)) (justify left bottom mirror))
    )
    (fp_text user "License: Apache-2.0" (at -0.95 -5.169 180) (layer "B.Fab") hide
      (effects (font (size 0.7 0.7) (thickness 0.15)) (justify left bottom mirror))
    )
    (fp_rect (start -0.93 0.47) (end 0.93 -0.47) (layer "B.CrtYd") (width 0.05) (fill none))
    (fp_rect (start -0.5 0.25) (end 0.5 -0.25) (layer "B.Fab") (width 0.15) (fill none))
    (pad "1" smd roundrect (at -0.485 0) (size 0.59 0.64) (layers "B.Cu" "B.Paste" "B.Mask") (roundrect_rratio 0.25)
      (net 131 "3V3_SYS") (pintype "passive"))
    (pad "2" smd roundrect (at 0.485 0) (size 0.59 0.64) (layers "B.Cu" "B.Paste" "B.Mask") (roundrect_rratio 0.25)
      (net 121 "M2_ALERT") (pintype "passive"))
  )
	(footprint "sa800u-baseboard-hw-footprints:R_0402_1005Metric" (layer "B.Cu")
    (tedit 5FD9C158)
    (at 140.7 94 -90)
    (descr "Resistor SMD 0402")
    (tags "resistor SMD 0402")
    (property "Author" "Antmicro")
    (property "License" "Apache-2.0")
    (property "MPN" "CR0402-FX-1002GLF")
    (property "Manufacturer" "Bourns")
    (property "Sheetfile" "m2.kicad_sch")
    (property "Sheetname" "M2")
    (property "Tolerance" "1%")
    (property "Val" "10k")
    (attr smd)
    (fp_text reference "R90" (at 0.9 -0.4 90) (layer "B.SilkS")
      (effects (font (size 0.7 0.7) (thickness 0.15)) (justify left bottom mirror))
    )
    (fp_text value "R_10k_0402" (at 0 -1.4 90) (layer "B.Fab")
      (effects (font (size 0.7 0.7) (thickness 0.15)) (justify left bottom mirror))
    )
    (fp_text user "${REFERENCE}" (at -0.95 -3.168 90) (layer "B.Fab") hide
      (effects (font (size 0.7 0.7) (thickness 0.15)) (justify left bottom mirror))
    )
    (fp_text user "Author: Antmicro" (at -0.95 -4.169 90) (layer "B.Fab") hide
      (effects (font (size 0.7 0.7) (thickness 0.15)) (justify left bottom mirror))
    )
    (fp_text user "License: Apache-2.0" (at -0.95 -5.169 90) (layer "B.Fab") hide
      (effects (font (size 0.7 0.7) (thickness 0.15)) (justify left bottom mirror))
    )
    (fp_rect (start -0.93 0.47) (end 0.93 -0.47) (layer "B.CrtYd") (width 0.05) (fill none))
    (fp_rect (start -0.5 0.25) (end 0.5 -0.25) (layer "B.Fab") (width 0.15) (fill none))
    (pad "1" smd roundrect (at -0.485 0 270) (size 0.59 0.64) (layers "B.Cu" "B.Paste" "B.Mask") (roundrect_rratio 0.25)
      (net 131 "3V3_SYS") (pintype "passive"))
    (pad "2" smd roundrect (at 0.485 0 270) (size 0.59 0.64) (layers "B.Cu" "B.Paste" "B.Mask") (roundrect_rratio 0.25)
      (net 120 "PCIE0_CLKREQ_N") (pintype "passive"))
  )
	(footprint "sa800u-baseboard-hw-footprints:R_0402_1005Metric" (layer "B.Cu")
    (tedit 5FD9C158)
    (at 139.74 94 -90)
    (descr "Resistor SMD 0402")
    (tags "resistor SMD 0402")
    (property "Author" "Antmicro")
    (property "License" "Apache-2.0")
    (property "MPN" "CR0402-FX-1002GLF")
    (property "Manufacturer" "Bourns")
    (property "Sheetfile" "m2.kicad_sch")
    (property "Sheetname" "M2")
    (property "Tolerance" "1%")
    (property "Val" "10k")
    (attr smd)
    (fp_text reference "R91" (at 0.9 -0.4 90) (layer "B.SilkS")
      (effects (font (size 0.7 0.7) (thickness 0.15)) (justify left bottom mirror))
    )
    (fp_text value "R_10k_0402" (at 0 -1.4 90) (layer "B.Fab")
      (effects (font (size 0.7 0.7) (thickness 0.15)) (justify left bottom mirror))
    )
    (fp_text user "Author: Antmicro" (at -0.95 -4.169 90) (layer "B.Fab") hide
      (effects (font (size 0.7 0.7) (thickness 0.15)) (justify left bottom mirror))
    )
    (fp_text user "License: Apache-2.0" (at -0.95 -5.169 90) (layer "B.Fab") hide
      (effects (font (size 0.7 0.7) (thickness 0.15)) (justify left bottom mirror))
    )
    (fp_text user "${REFERENCE}" (at -0.95 -3.168 90) (layer "B.Fab") hide
      (effects (font (size 0.7 0.7) (thickness 0.15)) (justify left bottom mirror))
    )
    (fp_rect (start -0.93 0.47) (end 0.93 -0.47) (layer "B.CrtYd") (width 0.05) (fill none))
    (fp_rect (start -0.5 0.25) (end 0.5 -0.25) (layer "B.Fab") (width 0.15) (fill none))
    (pad "1" smd roundrect (at -0.485 0 270) (size 0.59 0.64) (layers "B.Cu" "B.Paste" "B.Mask") (roundrect_rratio 0.25)
      (net 131 "3V3_SYS") (pintype "passive"))
    (pad "2" smd roundrect (at 0.485 0 270) (size 0.59 0.64) (layers "B.Cu" "B.Paste" "B.Mask") (roundrect_rratio 0.25)
      (net 124 "PCIE0_RST_N") (pintype "passive"))
  )
	(footprint "sa800u-baseboard-hw-footprints:C_0402_1005Metric" (layer "B.Cu")
    (tedit 616D63CF)
    (at 137.75 134.95 90)
    (descr "Capacitor SMD 0402")
    (tags "capacitor SMD 0402")
    (property "Author" "Antmicro")
    (property "DNP" "DNP")
    (property "Dielectric" "C0G")
    (property "License" "Apache-2.0")
    (property "MPN" "GCM1555C1H100GA16D")
    (property "Manufacturer" "Murata")
    (property "Sheetfile" "hdmi-converter.kicad_sch")
    (property "Sheetname" "HDMI converter")
    (property "Val" "10p")
    (property "Voltage" "50V")
    (attr exclude_from_pos_files)
    (fp_text reference "C56" (at -0.85 0.37 270) (layer "B.SilkS")
      (effects (font (size 0.7 0.7) (thickness 0.15)) (justify left bottom mirror))
    )
    (fp_text value "C_10p_0402" (at 0 -1.4 270) (layer "B.Fab")
      (effects (font (size 0.7 0.7) (thickness 0.15)) (justify left bottom mirror))
    )
    (fp_text user "License: Apache-2.0" (at -0.932 -5.17 270) (layer "B.Fab") hide
      (effects (font (size 0.7 0.7) (thickness 0.15)) (justify left bottom mirror))
    )
    (fp_text user "Author: Antmicro" (at -0.932 -4.17 270) (layer "B.Fab") hide
      (effects (font (size 0.7 0.7) (thickness 0.15)) (justify left bottom mirror))
    )
    (fp_text user "${REFERENCE}" (at -0.932 -3.168 270) (layer "B.Fab") hide
      (effects (font (size 0.7 0.7) (thickness 0.15)) (justify left bottom mirror))
    )
    (fp_rect (start -0.94 0.47) (end 0.94 -0.47) (layer "B.CrtYd") (width 0.05) (fill none))
    (fp_rect (start -0.499 0.249) (end 0.499 -0.249) (layer "B.Fab") (width 0.15) (fill none))
    (pad "1" smd roundrect (at -0.484 0 90) (size 0.59 0.64) (layers "B.Cu" "B.Paste" "B.Mask") (roundrect_rratio 0.25)
      (net 206 "/HDMI converter/HDMI_CLK_P") (pintype "passive"))
    (pad "2" smd roundrect (at 0.484 0 90) (size 0.59 0.64) (layers "B.Cu" "B.Paste" "B.Mask") (roundrect_rratio 0.25)
      (net 1 "GND") (pintype "passive"))
  )
	(footprint "sa800u-baseboard-hw-footprints:R_0402_1005Metric" (layer "B.Cu")
    (tedit 5FD9C158)
    (at 121.8 115.9 -90)
    (descr "Resistor SMD 0402")
    (tags "resistor SMD 0402")
    (property "Author" "Antmicro")
    (property "License" "Apache-2.0")
    (property "MPN" "CR0402-FX-1002GLF")
    (property "Manufacturer" "Bourns")
    (property "Sheetfile" "hdmi-converter.kicad_sch")
    (property "Sheetname" "HDMI converter")
    (property "Tolerance" "1%")
    (property "Val" "10k")
    (attr smd)
    (fp_text reference "R17" (at -1.22 -2.38 90) (layer "B.SilkS")
      (effects (font (size 0.7 0.7) (thickness 0.15)) (justify left bottom mirror))
    )
    (fp_text value "R_10k_0402" (at 0 -1.4 90) (layer "B.Fab")
      (effects (font (size 0.7 0.7) (thickness 0.15)) (justify left bottom mirror))
    )
    (fp_text user "License: Apache-2.0" (at -0.95 -5.169 90) (layer "B.Fab") hide
      (effects (font (size 0.7 0.7) (thickness 0.15)) (justify left bottom mirror))
    )
    (fp_text user "Author: Antmicro" (at -0.95 -4.169 90) (layer "B.Fab") hide
      (effects (font (size 0.7 0.7) (thickness 0.15)) (justify left bottom mirror))
    )
    (fp_text user "${REFERENCE}" (at -0.95 -3.168 90) (layer "B.Fab") hide
      (effects (font (size 0.7 0.7) (thickness 0.15)) (justify left bottom mirror))
    )
    (fp_rect (start -0.93 0.47) (end 0.93 -0.47) (layer "B.CrtYd") (width 0.05) (fill none))
    (fp_rect (start -0.5 0.25) (end 0.5 -0.25) (layer "B.Fab") (width 0.15) (fill none))
    (pad "1" smd roundrect (at -0.485 0 270) (size 0.59 0.64) (layers "B.Cu" "B.Paste" "B.Mask") (roundrect_rratio 0.25)
      (net 131 "3V3_SYS") (pintype "passive"))
    (pad "2" smd roundrect (at 0.485 0 270) (size 0.59 0.64) (layers "B.Cu" "B.Paste" "B.Mask") (roundrect_rratio 0.25)
      (net 186 "/HDMI converter/LT9611_RST_N") (pintype "passive"))
  )
	(footprint "sa800u-baseboard-hw-footprints:R_0603_1608Metric" (layer "B.Cu")
    (tedit 5D5D3E92)
    (at 68.6 121.875 90)
    (descr "Resistor SMD 0603")
    (tags "resistor SMD 0603")
    (property "Author" "Antmicro")
    (property "License" "Apache-2.0")
    (property "MPN" "CR0603-FX-2002ELF")
    (property "Manufacturer" "Bourns")
    (property "Sheetfile" "poe.kicad_sch")
    (property "Sheetname" "PoE")
    (property "Tolerance" "1%")
    (property "Val" "20k")
    (attr smd)
    (fp_text reference "R149" (at 1.395 -0.52 270) (layer "B.SilkS")
      (effects (font (size 0.7 0.7) (thickness 0.15)) (justify left bottom mirror))
    )
    (fp_text value "R_20k_0603" (at 0 -1.6 270) (layer "B.Fab")
      (effects (font (size 0.7 0.7) (thickness 0.15)) (justify left bottom mirror))
    )
    (fp_text user "${REFERENCE}" (at -1.25 -3.898 270) (layer "B.Fab") hide
      (effects (font (size 0.7 0.7) (thickness 0.15)) (justify left bottom mirror))
    )
    (fp_text user "Author: Antmicro" (at -1.25 -4.9 270) (layer "B.Fab") hide
      (effects (font (size 0.7 0.7) (thickness 0.15)) (justify left bottom mirror))
    )
    (fp_text user "License: Apache-2.0" (at -1.25 -5.9 270) (layer "B.Fab") hide
      (effects (font (size 0.7 0.7) (thickness 0.15)) (justify left bottom mirror))
    )
    (fp_line (start -0.3 -0.3) (end 0.3 -0.3) (layer "B.SilkS") (width 0.15))
    (fp_line (start -0.3 0.3) (end 0.3 0.3) (layer "B.SilkS") (width 0.15))
    (fp_rect (start -1.25 0.7) (end 1.25 -0.7) (layer "B.CrtYd") (width 0.05) (fill none))
    (fp_rect (start -0.8 0.4) (end 0.8 -0.4) (layer "B.Fab") (width 0.15) (fill none))
    (pad "1" smd roundrect (at -0.7 0 90) (size 0.6 0.8) (layers "B.Cu" "B.Paste" "B.Mask") (roundrect_rratio 0.2)
      (net 73 "/PoE/VDD_POE") (pintype "passive"))
    (pad "2" smd roundrect (at 0.7 0 90) (size 0.6 0.8) (layers "B.Cu" "B.Paste" "B.Mask") (roundrect_rratio 0.2)
      (net 380 "Net-(D32-Pad1)") (pintype "passive"))
  )
	(footprint "sa800u-baseboard-hw-footprints:R_0402_1005Metric" (layer "B.Cu")
    (tedit 5FD9C158)
    (at 121.85 121.9)
    (descr "Resistor SMD 0402")
    (tags "resistor SMD 0402")
    (property "Author" "Antmicro")
    (property "License" "Apache-2.0")
    (property "MPN" "CR0402-FX-1002GLF")
    (property "Manufacturer" "Bourns")
    (property "Sheetfile" "psu.kicad_sch")
    (property "Sheetname" "PSU")
    (property "Tolerance" "1%")
    (property "Val" "10k")
    (attr smd)
    (fp_text reference "R128" (at -0.84 0.37 180) (layer "B.SilkS")
      (effects (font (size 0.7 0.7) (thickness 0.15)) (justify left bottom mirror))
    )
    (fp_text value "R_10k_0402" (at 0 -1.4 180) (layer "B.Fab")
      (effects (font (size 0.7 0.7) (thickness 0.15)) (justify left bottom mirror))
    )
    (fp_text user "License: Apache-2.0" (at -0.95 -5.169 180) (layer "B.Fab") hide
      (effects (font (size 0.7 0.7) (thickness 0.15)) (justify left bottom mirror))
    )
    (fp_text user "Author: Antmicro" (at -0.95 -4.169 180) (layer "B.Fab") hide
      (effects (font (size 0.7 0.7) (thickness 0.15)) (justify left bottom mirror))
    )
    (fp_text user "${REFERENCE}" (at -0.95 -3.168 180) (layer "B.Fab") hide
      (effects (font (size 0.7 0.7) (thickness 0.15)) (justify left bottom mirror))
    )
    (fp_rect (start -0.93 0.47) (end 0.93 -0.47) (layer "B.CrtYd") (width 0.05) (fill none))
    (fp_rect (start -0.5 0.25) (end 0.5 -0.25) (layer "B.Fab") (width 0.15) (fill none))
    (pad "1" smd roundrect (at -0.485 0) (size 0.59 0.64) (layers "B.Cu" "B.Paste" "B.Mask") (roundrect_rratio 0.25)
      (net 320 "1V2_SYS_EN") (pintype "passive"))
    (pad "2" smd roundrect (at 0.485 0) (size 0.59 0.64) (layers "B.Cu" "B.Paste" "B.Mask") (roundrect_rratio 0.25)
      (net 408 "Net-(R128-Pad2)") (pintype "passive"))
  )
)
